# T6G (Grand Teton) — schematic netlist excerpt (pin names and nets, part order shuffled) for the footprints in the layout excerpt that follows; sources: Cadence DE-HDL packaged netlist, KiCad conversion of 04192023_DAF0TMB3IC0_F0TG_MB_C_brd_V02_OCP.brd

C1113  Q_CAP  22UF 16V 20% EMPTY  pkg C0805  page 169 : A = P12V_AUX_DSC_S1 ; B = GND
C2412  Q_CAP  22UF 4V 20% X6S  pkg C0402  page 74 : A = PVDDCR_SOC_P1 ; B = GND
C72  Q_CAP  0.1UF 25V 10% X7R  pkg 0402  page 133 : A = P3V3_AUX ; B = GND

(kicad_pcb
	(version 20260206)
	(generator "pcbnew")
	(generator_version "10.0")
	(general
		(thickness 1.6)
		(legacy_teardrops no)
	)
	(paper "A4")
	(title_block
		(title "04192023_DAF0TMB3IC0_F0TG_MB_C_brd_V02_OCP.brd")
		(comment 1 "Grand Teton / footprints 3943-3945 of 8354")
	)
	(layers
		(0 "F.Cu" signal "TOP")
		(4 "In1.Cu" signal "GND")
		(6 "In2.Cu" signal "IN1")
		(8 "In3.Cu" signal "GND1")
		(10 "In4.Cu" signal "IN2")
		(12 "In5.Cu" signal "GND2")
		(14 "In6.Cu" signal "IN3")
		(16 "In7.Cu" signal "GND3")
		(18 "In8.Cu" signal "VCC")
		(20 "In9.Cu" signal "VCC1")
		(22 "In10.Cu" signal "GND4")
		(24 "In11.Cu" signal "IN4")
		(26 "In12.Cu" signal "GND5")
		(28 "In13.Cu" signal "IN5")
		(30 "In14.Cu" signal "GND6")
		(32 "In15.Cu" signal "IN6")
		(34 "In16.Cu" signal "GND7")
		(2 "B.Cu" signal "BOTTOM")
		(9 "F.Adhes" user "F.Adhesive")
		(11 "B.Adhes" user "B.Adhesive")
		(13 "F.Paste" user "Package Geometry/Pastemask Top")
		(15 "B.Paste" user "Package Geometry/Pastemask Bottom")
		(5 "F.SilkS" user "Ref Des/Silkscreen Top")
		(7 "B.SilkS" user "Ref Des/Silkscreen Bottom")
		(1 "F.Mask" user "Board Geometry/Soldermask Top")
		(3 "B.Mask" user "Board Geometry/Soldermask Bottom")
		(17 "Dwgs.User" user "User.Drawings")
		(19 "Cmts.User" user "User.Comments")
		(21 "Eco1.User" user "User.Eco1")
		(23 "Eco2.User" user "User.Eco2")
		(25 "Edge.Cuts" user "Board Geometry/Outline")
		(27 "Margin" user)
		(31 "F.CrtYd" user "Package Geometry/Place Bound Top")
		(29 "B.CrtYd" user "Package Geometry/Place Bound Bottom")
		(35 "F.Fab" user "Ref Des/Assembly Top")
		(33 "B.Fab" user "Ref Des/Assembly Bottom")
	)
	(footprint ""
		(layer "F.Cu")
		(at 41.11244 -105.2195)
		(property "Reference" "C1113"
			(at 0 0 0)
			(layer "F.SilkS")
			(hide yes)
			(effects
				(font
					(size 1.27 1.27)
				)
			)
		)
		(property "Value" ""
			(at 0 0 0)
			(layer "F.Fab")
			(effects
				(font
					(size 1.27 1.27)
				)
			)
		)
		(duplicate_pad_numbers_are_jumpers no)
		(fp_line
			(start -1.524 -0.762)
			(end 1.524 -0.762)
			(stroke
				(width 0.1524)
				(type default)
			)
			(layer "F.SilkS")
		)
		(fp_line
			(start -1.524 0.762)
			(end -1.524 -0.762)
			(stroke
				(width 0.1524)
				(type default)
			)
			(layer "F.SilkS")
		)
		(fp_line
			(start 1.524 -0.762)
			(end 1.524 0.762)
			(stroke
				(width 0.1524)
				(type default)
			)
			(layer "F.SilkS")
		)
		(fp_line
			(start 1.524 0.762)
			(end -1.524 0.762)
			(stroke
				(width 0.1524)
				(type default)
			)
			(layer "F.SilkS")
		)
		(fp_line
			(start -1.1049 -0.724916)
			(end -1.1049 0.724916)
			(stroke
				(width 0.1)
				(type default)
			)
			(layer "F.Fab")
		)
		(fp_line
			(start -1.1049 0.724916)
			(end 1.1049 0.724916)
			(stroke
				(width 0.1)
				(type default)
			)
			(layer "F.Fab")
		)
		(fp_line
			(start 1.1049 -0.724916)
			(end -1.1049 -0.724916)
			(stroke
				(width 0.1)
				(type default)
			)
			(layer "F.Fab")
		)
		(fp_line
			(start 1.1049 0.724916)
			(end 1.1049 -0.724916)
			(stroke
				(width 0.1)
				(type default)
			)
			(layer "F.Fab")
		)
		(pad "1" smd rect
			(at -0.889 0 180)
			(size 1.016 1.27)
			(layers "F.Cu" "F.Mask" "F.Paste")
			(net "P12V_AUX_DSC_S1")
		)
		(pad "2" smd rect
			(at 0.889 0 180)
			(size 1.016 1.27)
			(layers "F.Cu" "F.Mask" "F.Paste")
			(net "GND")
		)
	)
	(footprint ""
		(layer "F.Cu")
		(at 370.813584 -15.236952 90)
		(property "Reference" "C72"
			(at 0 0 90)
			(layer "F.SilkS")
			(hide yes)
			(effects
				(font
					(size 1.27 1.27)
				)
			)
		)
		(property "Value" ""
			(at 0 0 90)
			(layer "F.Fab")
			(effects
				(font
					(size 1.27 1.27)
				)
			)
		)
		(duplicate_pad_numbers_are_jumpers no)
		(fp_line
			(start 0.7874 -0.4064)
			(end 0.7874 0.4064)
			(stroke
				(width 0.1524)
				(type default)
			)
			(layer "F.SilkS")
		)
		(fp_line
			(start -0.7874 -0.4064)
			(end 0.7874 -0.4064)
			(stroke
				(width 0.1524)
				(type default)
			)
			(layer "F.SilkS")
		)
		(fp_line
			(start 0.7874 0.4064)
			(end -0.7874 0.4064)
			(stroke
				(width 0.1524)
				(type default)
			)
			(layer "F.SilkS")
		)
		(fp_line
			(start -0.7874 0.4064)
			(end -0.7874 -0.4064)
			(stroke
				(width 0.1524)
				(type default)
			)
			(layer "F.SilkS")
		)
		(fp_line
			(start -0.12065 -0.305054)
			(end -0.12065 -0.2794)
			(stroke
				(width 0.1)
				(type default)
			)
			(layer "F.Fab")
		)
		(fp_line
			(start -0.67945 -0.305054)
			(end -0.12065 -0.305054)
			(stroke
				(width 0.1)
				(type default)
			)
			(layer "F.Fab")
		)
		(fp_line
			(start 0.67945 -0.3048)
			(end 0.67945 0.3048)
			(stroke
				(width 0.1)
				(type default)
			)
			(layer "F.Fab")
		)
		(fp_line
			(start 0.12065 -0.3048)
			(end 0.67945 -0.3048)
			(stroke
				(width 0.1)
				(type default)
			)
			(layer "F.Fab")
		)
		(fp_line
			(start 0.12065 -0.2794)
			(end 0.12065 -0.3048)
			(stroke
				(width 0.1)
				(type default)
			)
			(layer "F.Fab")
		)
		(fp_line
			(start -0.12065 -0.2794)
			(end 0.12065 -0.2794)
			(stroke
				(width 0.1)
				(type default)
			)
			(layer "F.Fab")
		)
		(fp_line
			(start 0.120396 0.2794)
			(end -0.12065 0.2794)
			(stroke
				(width 0.1)
				(type default)
			)
			(layer "F.Fab")
		)
		(fp_line
			(start -0.12065 0.2794)
			(end -0.12065 0.3048)
			(stroke
				(width 0.1)
				(type default)
			)
			(layer "F.Fab")
		)
		(fp_line
			(start 0.67945 0.3048)
			(end 0.120396 0.3048)
			(stroke
				(width 0.1)
				(type default)
			)
			(layer "F.Fab")
		)
		(fp_line
			(start 0.120396 0.3048)
			(end 0.120396 0.2794)
			(stroke
				(width 0.1)
				(type default)
			)
			(layer "F.Fab")
		)
		(fp_line
			(start -0.12065 0.3048)
			(end -0.67945 0.3048)
			(stroke
				(width 0.1)
				(type default)
			)
			(layer "F.Fab")
		)
		(fp_line
			(start -0.67945 0.3048)
			(end -0.67945 -0.305054)
			(stroke
				(width 0.1)
				(type default)
			)
			(layer "F.Fab")
		)
		(pad "1" smd circle
			(at -0.40005 0 90)
			(size 0 0)
			(layers "F.Cu" "F.Mask" "F.Paste")
			(net "P3V3_AUX")
		)
		(pad "2" smd circle
			(at 0.40005 0 90)
			(size 0 0)
			(layers "F.Cu" "F.Mask" "F.Paste")
			(net "GND")
		)
	)
	(footprint ""
		(layer "F.Cu")
		(at 107.675934 -256.012442 90)
		(property "Reference" "C2412"
			(at 0 0 90)
			(layer "F.SilkS")
			(hide yes)
			(effects
				(font
					(size 1.27 1.27)
				)
			)
		)
		(property "Value" ""
			(at 0 0 90)
			(layer "F.Fab")
			(effects
				(font
					(size 1.27 1.27)
				)
			)
		)
		(duplicate_pad_numbers_are_jumpers no)
		(fp_line
			(start 0.7874 -0.4064)
			(end 0.7874 0.4064)
			(stroke
				(width 0.1524)
				(type default)
			)
			(layer "F.SilkS")
		)
		(fp_line
			(start -0.7874 -0.4064)
			(end 0.7874 -0.4064)
			(stroke
				(width 0.1524)
				(type default)
			)
			(layer "F.SilkS")
		)
		(fp_line
			(start 0.7874 0.4064)
			(end -0.7874 0.4064)
			(stroke
				(width 0.1524)
				(type default)
			)
			(layer "F.SilkS")
		)
		(fp_line
			(start -0.7874 0.4064)
			(end -0.7874 -0.4064)
			(stroke
				(width 0.1524)
				(type default)
			)
			(layer "F.SilkS")
		)
		(fp_line
			(start -0.12065 -0.305054)
			(end -0.12065 -0.2794)
			(stroke
				(width 0.1)
				(type default)
			)
			(layer "F.Fab")
		)
		(fp_line
			(start -0.67945 -0.305054)
			(end -0.12065 -0.305054)
			(stroke
				(width 0.1)
				(type default)
			)
			(layer "F.Fab")
		)
		(fp_line
			(start 0.67945 -0.3048)
			(end 0.67945 0.3048)
			(stroke
				(width 0.1)
				(type default)
			)
			(layer "F.Fab")
		)
		(fp_line
			(start 0.12065 -0.3048)
			(end 0.67945 -0.3048)
			(stroke
				(width 0.1)
				(type default)
			)
			(layer "F.Fab")
		)
		(fp_line
			(start 0.12065 -0.2794)
			(end 0.12065 -0.3048)
			(stroke
				(width 0.1)
				(type default)
			)
			(layer "F.Fab")
		)
		(fp_line
			(start -0.12065 -0.2794)
			(end 0.12065 -0.2794)
			(stroke
				(width 0.1)
				(type default)
			)
			(layer "F.Fab")
		)
		(fp_line
			(start 0.120396 0.2794)
			(end -0.12065 0.2794)
			(stroke
				(width 0.1)
				(type default)
			)
			(layer "F.Fab")
		)
		(fp_line
			(start -0.12065 0.2794)
			(end -0.12065 0.3048)
			(stroke
				(width 0.1)
				(type default)
			)
			(layer "F.Fab")
		)
		(fp_line
			(start 0.67945 0.3048)
			(end 0.120396 0.3048)
			(stroke
				(width 0.1)
				(type default)
			)
			(layer "F.Fab")
		)
		(fp_line
			(start 0.120396 0.3048)
			(end 0.120396 0.2794)
			(stroke
				(width 0.1)
				(type default)
			)
			(layer "F.Fab")
		)
		(fp_line
			(start -0.12065 0.3048)
			(end -0.67945 0.3048)
			(stroke
				(width 0.1)
				(type default)
			)
			(layer "F.Fab")
		)
		(fp_line
			(start -0.67945 0.3048)
			(end -0.67945 -0.305054)
			(stroke
				(width 0.1)
				(type default)
			)
			(layer "F.Fab")
		)
		(pad "1" smd circle
			(at -0.40005 0 90)
			(size 0 0)
			(layers "F.Cu" "F.Mask" "F.Paste")
			(net "PVDDCR_SOC_P1")
		)
		(pad "2" smd circle
			(at 0.40005 0 90)
			(size 0 0)
			(layers "F.Cu" "F.Mask" "F.Paste")
			(net "GND")
		)
	)
)
